# BASEBOARD_FAB2 (Tioga Pass) — schematic parts with pin connectivity, parts 1157–1334 of 4751; source: Cadence DE-HDL packaged netlist (pstxprt.dat, pstxnet.dat, pstchip.dat)

C5L7  CAP_A  47UF 4V 20% X5R  pkg 0603V  page 220 : 1 = PVDDQ_DEF ; 2 = GND
C5L8  CAP_A  47UF 4V 20% X5R  pkg 0603V  page 220 : 1 = PVDDQ_DEF ; 2 = GND
C5L9  CAP_A  47UF 4V 20% X5R  pkg 0603V  page 220 : 1 = PVDDQ_DEF ; 2 = GND
C5L10  CAP_A  47UF 4V 20% X5R  pkg 0603V  page 220 : 1 = PVDDQ_DEF ; 2 = GND
C5L11  CAP_A  47UF 4V 20% X5R  pkg 0603V  page 220 : 1 = PVDDQ_DEF ; 2 = GND
C5L12  CAP_A  47UF 4V 20% X5R  pkg 0603V  page 220 : 1 = PVDDQ_DEF ; 2 = GND
C5L13  CAP_A  47UF 4V 20% X5R  pkg 0603V  page 220 : 1 = PVDDQ_DEF ; 2 = GND
C5L14  CAP  100UF 4V 20% X5R  pkg 0805  page 220 : 1 = PVDDQ_DEF ; 2 = GND
C5L15  CAP_A  47UF 4V 20% X5R  pkg 0603V  page 220 : 1 = PVDDQ_DEF ; 2 = GND
C5M1  CAP_A  47UF 4V 20% X5R  pkg 0603V  page 220 : 1 = PVDDQ_DEF ; 2 = GND
C5M2  CAP_A  47UF 4V 20% X5R  pkg 0603V  page 220 : 1 = PVDDQ_DEF ; 2 = GND
C5M3  CAP_A  47UF 4V 20% X5R  pkg 0603V  page 220 : 1 = PVDDQ_DEF ; 2 = GND
C5M4  CAP_A  47UF 4V 20% X5R  pkg 0603V  page 220 : 1 = PVDDQ_DEF ; 2 = GND
C5M5  CAP_A  47UF 4V 20% X5R  pkg 0603V  page 220 : 1 = PVDDQ_DEF ; 2 = GND
C5M6  CAP_A  47UF 4V 20% X5R  pkg 0603V  page 220 : 1 = PVDDQ_DEF ; 2 = GND
C5M7  CAP_A  47UF 4V 20% X5R  pkg 0603V  page 220 : 1 = PVDDQ_DEF ; 2 = GND
C5M8  CAP  100UF 4V 20% X5R  pkg 0805  page 220 : 1 = PVDDQ_DEF ; 2 = GND
C5M9  CAP_A  47UF 4V 20% X5R  pkg 0603V  page 220 : 1 = PVDDQ_DEF ; 2 = GND
C5M10  CAP_A  47UF 4V 20% X5R  pkg 0603V  page 220 : 1 = PVDDQ_DEF ; 2 = GND
C5M11  CAP_A  47UF 4V 20% X5R  pkg 0603V  page 220 : 1 = PVDDQ_DEF ; 2 = GND
C5M12  CAP  100UF 4V 20% X5R  pkg 0805  page 220 : 1 = PVDDQ_DEF ; 2 = GND
C5M13  CAP_A  47UF 4V 20% X5R  pkg 0603V  page 222 : 1 = PVTT_DEF ; 2 = GND
C5P1  CAP  100UF 4V 20% X5R  pkg 0805  page 220 : 1 = PVDDQ_DEF ; 2 = GND
C5P2  CAP  100UF 4V 20% X5R  pkg 0805  page 220 : 1 = PVDDQ_DEF ; 2 = GND
C5P3  CAP  100UF 4V 20% X5R  pkg 0805  page 220 : 1 = PVDDQ_DEF ; 2 = GND
C5P4  CAP  100UF 4V 20% X5R  pkg 0805  page 220 : 1 = PVDDQ_DEF ; 2 = GND
C5P5  CAP  100UF 4V 20% X5R  pkg 0805  page 220 : 1 = PVDDQ_DEF ; 2 = GND
C5P6  CAP  100UF 4V 20% X5R  pkg 0805  page 220 : 1 = PVDDQ_DEF ; 2 = GND
C5P7  CAP  22UF 4V 20% X6S  pkg 0805LF  page 42 : 1 = PVSA_CPU0 ; 2 = GND
C5P8  CAP  22UF 4V 20% X6S  pkg 0805LF  page 42 : 1 = PVSA_CPU0 ; 2 = GND
C5P9  CAP  22UF 4V 20% X6S  pkg 0805LF  page 42 : 1 = PVSA_CPU0 ; 2 = GND
C5P10  CAP  100UF 4V 20% X5R  pkg 0805  page 42 : 1 = PVCCMCP_CPU0 ; 2 = GND
C5P11  CAP  100UF 4V 20% X5R  pkg 0805  page 42 : 1 = PVCCMCP_CPU0 ; 2 = GND
C5P12  CAP  100UF 4V 20% X5R  pkg 0805  page 42 : 1 = PVCCMCP_CPU0 ; 2 = GND
C5P13  CAP  100UF 4V 20% X5R  pkg 0805  page 42 : 1 = PVCCMCP_CPU0 ; 2 = GND
C5P14  CAP  47UF 4V 20% X6S  pkg 0805  page 42 : 1 = PVCCIN_CPU0 ; 2 = GND
C5P15  CAP  47UF 4V 20% X6S  pkg 0805  page 42 : 1 = PVCCIN_CPU0 ; 2 = GND
C5P16  CAP  47UF 4V 20% X6S  pkg 0805  page 42 : 1 = PVCCIN_CPU0 ; 2 = GND
C5P17  CAP  47UF 4V 20% X6S  pkg 0805  page 42 : 1 = PVCCIN_CPU0 ; 2 = GND
C5P18  CAP  100UF 4V 20% X5R  pkg 0805  page 42 : 1 = PVCCMCP_CPU0 ; 2 = GND
C5P19  CAP  100UF 4V 20% X5R  pkg 0805  page 42 : 1 = PVCCMCP_CPU0 ; 2 = GND
C5P20  CAP  100UF 4V 20% X5R  pkg 0805  page 42 : 1 = PVCCMCP_CPU0 ; 2 = GND
C5P21  CAP  100UF 4V 20% X5R  pkg 0805  page 42 : 1 = PVCCMCP_CPU0 ; 2 = GND
C5P22  CAP  47UF 4V 20% X6S  pkg 0805  page 42 : 1 = PVCCIN_CPU0 ; 2 = GND
C5P23  CAP  47UF 4V 20% X6S  pkg 0805  page 42 : 1 = PVCCIN_CPU0 ; 2 = GND
C5P24  CAP  47UF 4V 20% X6S  pkg 0805  page 42 : 1 = PVCCIN_CPU0 ; 2 = GND
C5P25  CAP  47UF 4V 20% X6S  pkg 0805  page 42 : 1 = PVCCIN_CPU0 ; 2 = GND
C5P26  CAP  47UF 4V 20% X6S  pkg 0805  page 42 : 1 = PVCCIN_CPU0 ; 2 = GND
C5P27  CAP  47UF 4V 20% X6S  pkg 0805  page 42 : 1 = PVCCIN_CPU0 ; 2 = GND
C5P28  CAP  100UF 4V 20% X5R  pkg 0805  page 42 : 1 = PVCCMCP_CPU0 ; 2 = GND
C5P29  CAP  100UF 4V 20% X5R  pkg 0805  page 42 : 1 = PVCCMCP_CPU0 ; 2 = GND
C5P30  CAP  100UF 4V 20% X5R  pkg 0805  page 42 : 1 = PVCCMCP_CPU0 ; 2 = GND
C5P31  CAP  100UF 4V 20% X5R  pkg 0805  page 42 : 1 = PVCCMCP_CPU0 ; 2 = GND
C5P32  CAP  47UF 4V 20% X6S  pkg 0805  page 42 : 1 = PVCCIN_CPU0 ; 2 = GND
C5P33  CAP  47UF 4V 20% X6S  pkg 0805  page 42 : 1 = PVCCIN_CPU0 ; 2 = GND
C5P34  CAP  47UF 4V 20% X6S  pkg 0805  page 42 : 1 = PVCCIN_CPU0 ; 2 = GND
C5P35  CAP  47UF 4V 20% X6S  pkg 0805  page 42 : 1 = PVCCIN_CPU0 ; 2 = GND
C5P36  CAP  47UF 4V 20% X6S  pkg 0805  page 42 : 1 = PVCCIN_CPU0 ; 2 = GND
C5P37  CAP  47UF 4V 20% X6S  pkg 0805  page 42 : 1 = PVCCIN_CPU0 ; 2 = GND
C5P38  CAP  100UF 4V 20% X5R  pkg 0805  page 217 : 1 = PVDDQ_ABC ; 2 = GND
C5P39  CAP  100UF 4V 20% X5R  pkg 0805  page 217 : 1 = PVDDQ_ABC ; 2 = GND
C5P40  CAP  47UF 4V 20% X6S  pkg 0805  page 42 : 1 = PVCCIN_CPU0 ; 2 = GND
C5P41  CAP  100UF 4V 20% X5R  pkg 0805  page 217 : 1 = PVDDQ_ABC ; 2 = GND
C5P42  CAP  100UF 4V 20% X5R  pkg 0805  page 217 : 1 = PVDDQ_ABC ; 2 = GND
C5P43  CAP  100UF 4V 20% X5R  pkg 0805  page 217 : 1 = PVDDQ_ABC ; 2 = GND
C5P44  CAP  100UF 4V 20% X5R  pkg 0805  page 217 : 1 = PVDDQ_ABC ; 2 = GND
C5T1  CAP_A  47UF 4V 20% X5R  pkg 0603V  page 217 : 1 = PVDDQ_ABC ; 2 = GND
C5T2  CAP_A  47UF 4V 20% X5R  pkg 0603V  page 217 : 1 = PVDDQ_ABC ; 2 = GND
C5T3  CAP_A  47UF 4V 20% X5R  pkg 0603V  page 221 : 1 = PVTT_ABC ; 2 = GND
C5T4  CAP_A  47UF 4V 20% X5R  pkg 0603V  page 217 : 1 = PVDDQ_ABC ; 2 = GND
C5T5  CAP_A  47UF 4V 20% X5R  pkg 0603V  page 217 : 1 = PVDDQ_ABC ; 2 = GND
C5T6  CAP_A  47UF 4V 20% X5R  pkg 0603V  page 217 : 1 = PVDDQ_ABC ; 2 = GND
C5T7  CAP_A  47UF 4V 20% X5R  pkg 0603V  page 217 : 1 = PVDDQ_ABC ; 2 = GND
C5T8  CAP_A  47UF 4V 20% X5R  pkg 0603V  page 217 : 1 = PVDDQ_ABC ; 2 = GND
C5T9  CAP_A  47UF 4V 20% X5R  pkg 0603V  page 217 : 1 = PVDDQ_ABC ; 2 = GND
C5T10  CAP_A  47UF 4V 20% X5R  pkg 0603V  page 217 : 1 = PVDDQ_ABC ; 2 = GND
C5T11  CAP_A  47UF 4V 20% X5R  pkg 0603V  page 217 : 1 = PVDDQ_ABC ; 2 = GND
C5T12  CAP_A  47UF 4V 20% X5R  pkg 0603V  page 217 : 1 = PVDDQ_ABC ; 2 = GND
C5T13  CAP_A  47UF 4V 20% X5R  pkg 0603V  page 217 : 1 = PVDDQ_ABC ; 2 = GND
C5U1  CAP  100UF 4V 20% X5R  pkg 0805  page 217 : 1 = PVDDQ_ABC ; 2 = GND
C5U2  CAP_A  47UF 4V 20% X5R  pkg 0603V  page 217 : 1 = PVDDQ_ABC ; 2 = GND
C5U3  CAP_A  47UF 4V 20% X5R  pkg 0603V  page 217 : 1 = PVDDQ_ABC ; 2 = GND
C5U4  CAP_A  47UF 4V 20% X5R  pkg 0603V  page 217 : 1 = PVDDQ_ABC ; 2 = GND
C5U5  CAP_A  47UF 4V 20% X5R  pkg 0603V  page 217 : 1 = PVDDQ_ABC ; 2 = GND
C5U6  CAP_A  47UF 4V 20% X5R  pkg 0603V  page 217 : 1 = PVDDQ_ABC ; 2 = GND
C5U7  CAP_A  47UF 4V 20% X5R  pkg 0603V  page 217 : 1 = PVDDQ_ABC ; 2 = GND
C5U8  CAP_A  47UF 4V 20% X5R  pkg 0603V  page 217 : 1 = PVDDQ_ABC ; 2 = GND
C5U9  CAP_A  47UF 4V 20% X5R  pkg 0603V  page 217 : 1 = PVDDQ_ABC ; 2 = GND
C5U10  CAP  100UF 4V 20% X5R  pkg 0805  page 217 : 1 = PVDDQ_ABC ; 2 = GND
C5U11  CAP_A  47UF 4V 20% X5R  pkg 0603V  page 217 : 1 = PVDDQ_ABC ; 2 = GND
C5U12  CAP  100UF 4V 20% X5R  pkg 0805  page 221 : 1 = PVTT_ABC ; 2 = GND
C5U13  CAP  100UF 4V 20% X5R  pkg 0805  page 217 : 1 = PVDDQ_ABC ; 2 = GND
C5U14  CAP  100UF 4V 20% X5R  pkg 0805  page 217 : 1 = PVDDQ_ABC ; 2 = GND
C5U15  CAP  100UF 4V 20% X5R  pkg 0805  page 217 : 1 = PVDDQ_ABC ; 2 = GND
C5U16  CAP  100UF 4V 20% X5R  pkg 0805  page 221 : 1 = PVTT_ABC ; 2 = GND
C5W1  CAP_A  22.0UF 4V 20% X6S  pkg 0603V  page 42 : 1 = PVCCMCP_CPU0 ; 2 = GND
C5W2  CAP_A  22.0UF 4V 20% X6S  pkg 0603V  page 42 : 1 = PVCCMCP_CPU0 ; 2 = GND
C6A1  CAP  22UF 4V 20% X6S  pkg 0805LF  page 219 : 1 = PVDDQ_DEF ; 2 = GND
C6A2  CAP  10UF 4V 20% X6S  pkg 0603LF  page 232 : 1 = PVPP_DEF ; 2 = GND
C6A3  CAP  10UF 4V 20% X6S  pkg 0603LF  page 232 : 1 = PVPP_DEF ; 2 = GND
C6A4  CAP  22UF 4V 20% X6S  pkg 0805LF  page 219 : 1 = PVDDQ_DEF ; 2 = GND
C6A5  CAPP  470UF 2.5V 20% ALUM  pkg 3018  page 220 : 1 = PVDDQ_DEF ; 2 = GND
C6A6  CAP  10UF 4V 20% X6S  pkg 0603LF  page 232 : 1 = PVPP_DEF ; 2 = GND
C6A7  CAP  10UF 4V 20% X6S  pkg 0603LF  page 232 : 1 = PVPP_DEF ; 2 = GND
C6B1  CAP  10UF 4V 20% X6S  pkg 0603LF  page 232 : 1 = PVPP_DEF ; 2 = GND
C6B2  CAP  10UF 4V 20% X6S  pkg 0603LF  page 232 : 1 = PVPP_DEF ; 2 = GND
C6B3  CAP  47UF 4V 20% X6S  pkg 0805  page 232 : 1 = PVPP_DEF ; 2 = GND
C6B4  CAP  0.22UF 16V 10% X7R  pkg 0402  page 105 : 1 = P3E_CPU0_PE1_PCH_TXN<15> ; 2 = P3E_CPU0_PE1_PCH_C_TXN<15>
C6B5  CAP  0.22UF 16V 10% X7R  pkg 0402  page 105 : 1 = P3E_CPU0_PE1_PCH_TXP<15> ; 2 = P3E_CPU0_PE1_PCH_C_TXP<15>
C6B6  CAP  0.22UF 16V 10% X7R  pkg 0402  page 105 : 1 = P3E_CPU0_PE1_PCH_TXN<14> ; 2 = P3E_CPU0_PE1_PCH_C_TXN<14>
C6B7  CAPP  330UF 6.3V 20% POSCAP  pkg 7343LF  page 232 : 1 = PVPP_DEF ; 2 = GND
C6B8  CAP  0.22UF 16V 10% X7R  pkg 0402  page 105 : 1 = P3E_CPU0_PE1_PCH_TXP<14> ; 2 = P3E_CPU0_PE1_PCH_C_TXP<14>
C6B9  CAP  0.22UF 16V 10% X7R  pkg 0402  page 105 : 1 = P3E_CPU0_PE1_PCH_TXN<13> ; 2 = P3E_CPU0_PE1_PCH_C_TXN<13>
C6B10  CAP  0.22UF 16V 10% X7R  pkg 0402  page 105 : 1 = P3E_CPU0_PE1_PCH_TXP<13> ; 2 = P3E_CPU0_PE1_PCH_C_TXP<13>
C6B11  CAP  0.22UF 16V 10% X7R  pkg 0402  page 105 : 1 = P3E_CPU0_PE1_PCH_TXN<12> ; 2 = P3E_CPU0_PE1_PCH_C_TXN<12>
C6B12  CAP  0.22UF 16V 10% X7R  pkg 0402  page 105 : 1 = P3E_CPU0_PE1_PCH_TXP<12> ; 2 = P3E_CPU0_PE1_PCH_C_TXP<12>
C6B13  CAP  0.22UF 16V 10% X7R  pkg 0402  page 105 : 1 = P3E_CPU0_PE1_PCH_TXP<11> ; 2 = P3E_CPU0_PE1_PCH_C_TXP<11>
C6B14  CAP  0.22UF 16V 10% X7R  pkg 0402  page 105 : 1 = P3E_CPU0_PE1_PCH_TXN<11> ; 2 = P3E_CPU0_PE1_PCH_C_TXN<11>
C6B15  CAP  0.22UF 16V 10% X7R  pkg 0402  page 105 : 1 = P3E_CPU0_PE1_PCH_TXN<10> ; 2 = P3E_CPU0_PE1_PCH_C_TXN<10>
C6B16  CAP  0.22UF 16V 10% X7R  pkg 0402  page 105 : 1 = P3E_CPU0_PE1_PCH_TXP<10> ; 2 = P3E_CPU0_PE1_PCH_C_TXP<10>
C6B17  CAP  0.22UF 16V 10% X7R  pkg 0402  page 105 : 1 = P3E_CPU0_PE1_PCH_TXN<9> ; 2 = P3E_CPU0_PE1_PCH_C_TXN<9>
C6B18  CAP  0.22UF 16V 10% X7R  pkg 0402  page 105 : 1 = P3E_CPU0_PE1_PCH_TXP<9> ; 2 = P3E_CPU0_PE1_PCH_C_TXP<9>
C6B19  CAP  0.22UF 16V 10% X7R  pkg 0402  page 105 : 1 = P3E_CPU0_PE1_PCH_TXN<8> ; 2 = P3E_CPU0_PE1_PCH_C_TXN<8>
C6B20  CAP  0.22UF 16V 10% X7R  pkg 0402  page 105 : 1 = P3E_CPU0_PE1_PCH_TXP<8> ; 2 = P3E_CPU0_PE1_PCH_C_TXP<8>
C6D1  CAP  10UF 4V 20% X6S  pkg 0603LF  page 38 : 1 = P1V8_MCP_CPU0 ; 2 = GND
C6D2  CAP_A  22.0UF 4V 20% X6S  pkg 0603V  page 42 : 1 = PVCCMCP_CPU0 ; 2 = GND
C6D3  CAP_A  22.0UF 4V 20% X6S  pkg 0603V  page 42 : 1 = PVCCIO_CPU0 ; 2 = GND
C6D4  CAP_A  22.0UF 4V 20% X6S  pkg 0603V  page 42 : 1 = PVCCIO_CPU0 ; 2 = GND
C6D5  CAP_A  22.0UF 4V 20% X6S  pkg 0603V  page 42 : 1 = PVCCMCP_CPU0 ; 2 = GND
C6D6  CAP_A  22.0UF 4V 20% X6S  pkg 0603V  page 42 : 1 = PVCCIO_CPU0 ; 2 = GND
C6D7  CAP_A  22.0UF 4V 20% X6S  pkg 0603V  page 42 : 1 = PVCCIO_CPU0 ; 2 = GND
C6D8  CAP_A  22.0UF 4V 20% X6S  pkg 0603V  page 42 : 1 = PVCCMCP_CPU0 ; 2 = GND
C6D9  CAP_A  22.0UF 4V 20% X6S  pkg 0603V  page 42 : 1 = PVCCIO_CPU0 ; 2 = GND
C6D10  CAP_A  22.0UF 4V 20% X6S  pkg 0603V  page 42 : 1 = PVCCIO_CPU0 ; 2 = GND
C6F1  CAP_A  0.1UF 16V 10% X7R  pkg 0402V  page 104 : 1 = P3V3 ; 2 = GND
C6F2  CAP_A  0.1UF 16V 10% X7R  pkg 0402V  page 99 : 1 = PVCCIO_CPU0 ; 2 = GND
C6F3  CAP_A  0.1UF 16V 10% X7R  pkg 0402V  page 99 : 1 = PVPP_ABC ; 2 = GND
C6F4  CAPP  330UF 6.3V 20% POSCAP  pkg 7343LF  page 231 : 1 = PVPP_ABC ; 2 = GND
C6F5  CAP  10UF 4V 20% X6S  pkg 0603LF  page 231 : 1 = PVPP_ABC ; 2 = GND
C6F6  CAP  10UF 4V 20% X6S  pkg 0603LF  page 231 : 1 = PVPP_ABC ; 2 = GND
C6G1  CAP  10UF 4V 20% X6S  pkg 0603LF  page 231 : 1 = PVPP_ABC ; 2 = GND
C6G2  CAP  10UF 4V 20% X6S  pkg 0603LF  page 231 : 1 = PVPP_ABC ; 2 = GND
C6G3  CAP  22UF 4V 20% X6S  pkg 0805LF  page 216 : 1 = PVDDQ_ABC ; 2 = GND
C6G4  CAP  10UF 4V 20% X6S  pkg 0603LF  page 231 : 1 = PVPP_ABC ; 2 = GND
C6G5  CAP  10UF 4V 20% X6S  pkg 0603LF  page 231 : 1 = PVPP_ABC ; 2 = GND
C6L1  CAP_A  0.01UF 25V 10% X7R  pkg 0402V  page 53 : 1 = M_F_VREF ; 2 = GND
C6L2  CAP_A  0.01UF 25V 10% X7R  pkg 0402V  page 98 : 1 = M_F_CPU_VREF ; 2 = GND
C6L3  CAP  10UF 4V 20% X6S  pkg 0603LF  page 222 : 1 = PVDDQ_DEF ; 2 = GND
C6L4  CAP  10UF 4V 20% X6S  pkg 0603LF  page 222 : 1 = PVDDQ_DEF ; 2 = GND
C6L5  CAP  10UF 4V 20% X6S  pkg 0603LF  page 230 : 1 = PVDDQ_KLM ; 2 = GND
C6L6  CAP_A  0.01UF 25V 10% X7R  pkg 0402V  page 51 : 1 = M_E_VREF ; 2 = GND
C6L7  CAP_A  0.01UF 25V 10% X7R  pkg 0402V  page 98 : 1 = M_E_CPU_VREF ; 2 = GND
C6L8  CAPP  220UF 4V 20% POSCAP  pkg 7343  page 234 : 1 = PVPP_KLM ; 2 = GND
C6L10  CAP  10UF 16V 10% X6S  pkg 0805  page 234 : 1 = VR_FET_SW_P12V_STBY_PVPP_KLM ; 2 = GND
C6L11  CAP  1.0UF 16V 10% X6S  pkg 0402  page 234 : 1 = VR_FET_SW_P12V_STBY_PVPP_KLM ; 2 = GND
C6L12  CAP  4.7UF 6.3V 10% X6S  pkg 0603  page 234 : 1 = VR_VB_PVPP_KLM ; 2 = AGND_PVPP_KLM
C6M1  CAP_A  0.01UF 25V 10% X7R  pkg 0402V  page 50 : 1 = M_D_VREF ; 2 = GND
C6M2  CAP_A  0.01UF 25V 10% X7R  pkg 0402V  page 98 : 1 = M_D_CPU_VREF ; 2 = GND
C6M3  CAP  10UF 16V 10% X6S  pkg 0805  page 234 : 1 = VR_FET_SW_P12V_STBY_PVPP_KLM ; 2 = GND
C6M5  CAP  10UF 16V 10% X6S  pkg 0805  page 234 : 1 = VR_FET_SW_P12V_STBY_PVPP_KLM ; 2 = GND
C6M6  CAP_A  0.1UF 16V 10% X7R  pkg 0402V  page 113 : 1 = JTAG_MCP_CPU1_TDI_R ; 2 = GND
C6N1  CAPP  470UF 2.5V 20% ALUM  pkg 3018  page 205 : 1 = PVSA_CPU0 ; 2 = GND
C6N2  CAP  10UF 16V 10% X6S  pkg 0805  page 205 : 1 = VR_FET_SW_P12V_STBY_PVCCIN_CPU0 ; 2 = GND
C6N3  CAP  10UF 16V 10% X6S  pkg 0805  page 205 : 1 = VR_FET_SW_P12V_STBY_PVCCIN_CPU0 ; 2 = GND
C6N4  CAPP  470UF 2.5V 20% ALUM  pkg 3018  page 205 : 1 = PVSA_CPU0 ; 2 = GND
C6N5  CAPP  68UF 16V 20% TANT  pkg 3018  page 195 : 1 = P12V_STBY ; 2 = GND
C6N6  CAP  10UF 16V 10% X6S  pkg 0805  page 205 : 1 = VR_FET_SW_P12V_STBY_PVCCIN_CPU0 ; 2 = GND
C6N7  CAP_A  22.0UF 4V 20% X6S  pkg 0603V  page 205 : 1 = PVSA_CPU0 ; 2 = GND
C6N8  CAP  10UF 16V 10% X6S  pkg 0805  page 202 : 1 = VR_FET_SW_P12V_STBY_PVCCIN_CPU0 ; 2 = GND
C6N9  CAPP  470UF 2.5V 20% ALUM  pkg 3018  page 203 : 1 = PVCCIN_CPU0 ; 2 = GND
C6N10  CAP  10UF 16V 10% X6S  pkg 0805  page 204 : 1 = VR_FET_SW_P12V_STBY_PVCCIN_CPU0 ; 2 = GND
C6N11  CAP  10UF 16V 10% X6S  pkg 0805  page 204 : 1 = VR_FET_SW_P12V_STBY_PVCCIN_CPU0 ; 2 = GND
C6P3  CAP_A  22.0UF 4V 20% X6S  pkg 0603V  page 203 : 1 = PVCCIN_CPU0 ; 2 = GND
C6P4  CAP_A  0.1UF 16V 10% X7R  pkg 0402V  page 102 : 1 = P3V3_DB1200 ; 2 = GND
C6P5  CAP_A  0.1UF 16V 10% X7R  pkg 0402V  page 102 : 1 = P3V3_DB1200 ; 2 = GND
C6P6  CAP_A  0.1UF 16V 10% X7R  pkg 0402V  page 102 : 1 = P3V3_DB1200 ; 2 = GND
C6P7  CAP  10UF 16V 10% X6S  pkg 0805  page 203 : 1 = VR_FET_SW_P12V_STBY_PVCCIN_CPU0 ; 2 = GND
C6P8  CAPP  470UF 2.5V 20% ALUM  pkg 3018  page 203 : 1 = PVCCIN_CPU0 ; 2 = GND
